(kicad_pcb
	(version 20260206)
	(generator "pcbnew")
	(generator_version "10.0")
	(general
		(thickness 1.6)
		(legacy_teardrops no)
	)
	(paper "A4")
	(title_block
		(title "timecard-production-celestica-r4006 — R4006-B0001-02_R01.brd")
		(comment 1 "Time Appliance Project (Time Card) / footprints 606-606 of 1113")
	)
	(layers
		(0 "F.Cu" signal "TOP")
		(4 "In1.Cu" signal "L02_GND1")
		(6 "In2.Cu" signal "L03_SIG1")
		(8 "In3.Cu" signal "L04_GND2")
		(10 "In4.Cu" signal "L05_VCC1")
		(12 "In5.Cu" signal "L06_VCC2")
		(14 "In6.Cu" signal "L07_GND3")
		(16 "In7.Cu" signal "L08_SIG2")
		(18 "In8.Cu" signal "L09_GND4")
		(2 "B.Cu" signal "BOTTOM")
		(9 "F.Adhes" user "F.Adhesive")
		(11 "B.Adhes" user "B.Adhesive")
		(13 "F.Paste" user "Package Geometry/Pastemask Top")
		(15 "B.Paste" user "Package Geometry/Pastemask Bottom")
		(5 "F.SilkS" user "Ref Des/Silkscreen Top")
		(7 "B.SilkS" user "Ref Des/Silkscreen Bottom")
		(1 "F.Mask" user "Board Geometry/Soldermask Top")
		(3 "B.Mask" user "Board Geometry/Soldermask Bottom")
		(17 "Dwgs.User" user "User.Drawings")
		(19 "Cmts.User" user "User.Comments")
		(21 "Eco1.User" user "User.Eco1")
		(23 "Eco2.User" user "User.Eco2")
		(25 "Edge.Cuts" user "Board Geometry/Outline")
		(27 "Margin" user)
		(31 "F.CrtYd" user "Package Geometry/Place Bound Top")
		(29 "B.CrtYd" user "Package Geometry/Place Bound Bottom")
		(35 "F.Fab" user "Ref Des/Assembly Top")
		(33 "B.Fab" user "Ref Des/Assembly Bottom")
	)
	(footprint ""
		(layer "F.Cu")
		(at 45.649896 -3.500374)
		(property "Reference" "GF1"
			(at 13.786104 -5.350256 0)
			(unlocked yes)
			(layer "F.SilkS")
			(effects
				(font
					(size 0.7874 0.5842)
					(thickness 0.1524)
				)
			)
		)
		(property "Value" ""
			(at 0 0 0)
			(layer "F.Fab")
			(effects
				(font
					(size 1.27 1.27)
				)
			)
		)
		(property "Device Type" "CONN_64P_GF-S_M_EF64_PCIE_P039A"
			(at 19.1262 4.810506 0)
			(unlocked yes)
			(layer "F.Fab")
			(hide yes)
			(effects
				(font
					(size 0.7874 0.5842)
					(thickness 0.1524)
				)
			)
		)
		(property "User Part Number" "PARTNUM*"
			(at 19.1262 5.978906 0)
			(unlocked yes)
			(layer "Cmts.User")
			(hide yes)
			(effects
				(font
					(size 0.7874 0.5842)
					(thickness 0.1524)
				)
			)
		)
		(duplicate_pad_numbers_are_jumpers no)
		(fp_poly
			(pts
				(xy -0.343408 4.0132) (xy 33.351216 4.0132) (xy 34.156904 3.207512) (xy 34.156904 -2.6035) (xy -1.149096 -2.6035)
				(xy -1.149096 3.207512)
			)
			(stroke
				(width 0)
				(type default)
			)
			(fill no)
			(layer "B.CrtYd")
		)
		(fp_poly
			(pts
				(xy -0.343408 4.0132) (xy 33.351216 4.0132) (xy 34.156904 3.207512) (xy 34.156904 -2.6035) (xy -1.149096 -2.6035)
				(xy -1.149096 3.207512)
			)
			(stroke
				(width 0)
				(type default)
			)
			(fill no)
			(layer "F.CrtYd")
		)
		(fp_line
			(start -0.641096 2.9972)
			(end -0.641096 -5.715)
			(stroke
				(width 0.1)
				(type default)
			)
			(layer "B.Fab")
		)
		(fp_line
			(start -0.133096 3.5052)
			(end -0.641096 2.9972)
			(stroke
				(width 0.1)
				(type default)
			)
			(layer "B.Fab")
		)
		(fp_line
			(start 10.039604 3.5052)
			(end -0.133096 3.5052)
			(stroke
				(width 0.1)
				(type default)
			)
			(layer "B.Fab")
		)
		(fp_line
			(start 10.547604 -3.9497)
			(end 10.547604 2.9972)
			(stroke
				(width 0.1)
				(type default)
			)
			(layer "B.Fab")
		)
		(fp_line
			(start 10.547604 2.9972)
			(end 10.039604 3.5052)
			(stroke
				(width 0.1)
				(type default)
			)
			(layer "B.Fab")
		)
		(fp_line
			(start 12.452604 2.9972)
			(end 12.452604 -3.9497)
			(stroke
				(width 0.1)
				(type default)
			)
			(layer "B.Fab")
		)
		(fp_line
			(start 12.960604 3.5052)
			(end 12.452604 2.9972)
			(stroke
				(width 0.1)
				(type default)
			)
			(layer "B.Fab")
		)
		(fp_line
			(start 33.140904 3.5052)
			(end 12.960604 3.5052)
			(stroke
				(width 0.1)
				(type default)
			)
			(layer "B.Fab")
		)
		(fp_line
			(start 33.648904 -5.715)
			(end 33.648904 2.9972)
			(stroke
				(width 0.1)
				(type default)
			)
			(layer "B.Fab")
		)
		(fp_line
			(start 33.648904 2.9972)
			(end 33.140904 3.5052)
			(stroke
				(width 0.1)
				(type default)
			)
			(layer "B.Fab")
		)
		(fp_arc
			(start 10.547604 -3.9497)
			(mid 10.826576 -4.623236)
			(end 11.500104 -4.9022)
			(stroke
				(width 0.1)
				(type default)
			)
			(layer "B.Fab")
		)
		(fp_arc
			(start 11.500104 -4.9022)
			(mid 12.173614 -4.623218)
			(end 12.452604 -3.9497)
			(stroke
				(width 0.1)
				(type default)
			)
			(layer "B.Fab")
		)
		(fp_line
			(start -0.641096 2.9972)
			(end -0.641096 -5.715)
			(stroke
				(width 0.1)
				(type default)
			)
			(layer "F.Fab")
		)
		(fp_line
			(start -0.133096 3.5052)
			(end -0.641096 2.9972)
			(stroke
				(width 0.1)
				(type default)
			)
			(layer "F.Fab")
		)
		(fp_line
			(start 10.039604 3.5052)
			(end -0.133096 3.5052)
			(stroke
				(width 0.1)
				(type default)
			)
			(layer "F.Fab")
		)
		(fp_line
			(start 10.547604 -3.9497)
			(end 10.547604 2.9972)
			(stroke
				(width 0.1)
				(type default)
			)
			(layer "F.Fab")
		)
		(fp_line
			(start 10.547604 2.9972)
			(end 10.039604 3.5052)
			(stroke
				(width 0.1)
				(type default)
			)
			(layer "F.Fab")
		)
		(fp_line
			(start 12.452604 2.9972)
			(end 12.452604 -3.9497)
			(stroke
				(width 0.1)
				(type default)
			)
			(layer "F.Fab")
		)
		(fp_line
			(start 12.960604 3.5052)
			(end 12.452604 2.9972)
			(stroke
				(width 0.1)
				(type default)
			)
			(layer "F.Fab")
		)
		(fp_line
			(start 33.140904 3.5052)
			(end 12.960604 3.5052)
			(stroke
				(width 0.1)
				(type default)
			)
			(layer "F.Fab")
		)
		(fp_line
			(start 33.648904 -5.715)
			(end 33.648904 2.9972)
			(stroke
				(width 0.1)
				(type default)
			)
			(layer "F.Fab")
		)
		(fp_line
			(start 33.648904 2.9972)
			(end 33.140904 3.5052)
			(stroke
				(width 0.1)
				(type default)
			)
			(layer "F.Fab")
		)
		(fp_arc
			(start 10.547604 -3.9497)
			(mid 10.826576 -4.623236)
			(end 11.500104 -4.9022)
			(stroke
				(width 0.1)
				(type default)
			)
			(layer "F.Fab")
		)
		(fp_arc
			(start 11.500104 -4.9022)
			(mid 12.173614 -4.623218)
			(end 12.452604 -3.9497)
			(stroke
				(width 0.1)
				(type default)
			)
			(layer "F.Fab")
		)
		(fp_text user "B1"
			(at 2.991104 -6.620256 0)
			(unlocked yes)
			(layer "F.SilkS")
			(effects
				(font
					(size 0.7874 0.5842)
					(thickness 0.1524)
				)
			)
		)
		(fp_text user "B32"
			(at 31.185104 -4.588256 0)
			(unlocked yes)
			(layer "F.SilkS")
			(effects
				(font
					(size 0.7874 0.5842)
					(thickness 0.1524)
				)
			)
		)
		(fp_text user "A1"
			(at 1.467104 -6.112256 0)
			(unlocked yes)
			(layer "B.SilkS")
			(effects
				(font
					(size 0.7874 0.5842)
					(thickness 0.1524)
				)
				(justify mirror)
			)
		)
		(fp_text user "A32"
			(at 32.542734 -5.135626 270)
			(unlocked yes)
			(layer "B.SilkS")
			(effects
				(font
					(size 0.7874 0.5842)
					(thickness 0.1524)
				)
				(justify mirror)
			)
		)
		(fp_text user "A1"
			(at 0.1016 -3.774948 0)
			(unlocked yes)
			(layer "B.Fab")
			(effects
				(font
					(size 0.7874 0.5842)
					(thickness 0.1524)
				)
				(justify mirror)
			)
		)
		(fp_text user "A32"
			(at 32.328104 -3.965956 0)
			(unlocked yes)
			(layer "B.Fab")
			(effects
				(font
					(size 0.7874 0.5842)
					(thickness 0.1524)
				)
				(justify mirror)
			)
		)
		(fp_text user "B1"
			(at 0.1524 -3.774948 0)
			(unlocked yes)
			(layer "F.Fab")
			(effects
				(font
					(size 0.7874 0.5842)
					(thickness 0.1524)
				)
			)
		)
		(fp_text user "B32"
			(at 32.5628 -3.825748 0)
			(unlocked yes)
			(layer "F.Fab")
			(effects
				(font
					(size 0.7874 0.5842)
					(thickness 0.1524)
				)
			)
		)
		(pad "A1" smd rect
			(at 0 -0.4953)
			(size 0.7112 3.2004)
			(layers "F.Cu" "F.Mask" "F.Paste")
			(net "CARD_PRESENT")
		)
		(pad "A2" smd rect
			(at 0.999998 0)
			(size 0.7112 4.191)
			(layers "F.Cu" "F.Mask" "F.Paste")
			(net "XP12R0V_PCIE")
		)
		(pad "A3" smd rect
			(at 1.999996 0)
			(size 0.7112 4.191)
			(layers "F.Cu" "F.Mask" "F.Paste")
			(net "XP12R0V_PCIE")
		)
		(pad "A4" smd rect
			(at 2.999994 0)
			(size 0.7112 4.191)
			(layers "F.Cu" "F.Mask" "F.Paste")
			(net "SG")
		)
		(pad "A5" smd rect
			(at 3.999992 0)
			(size 0.7112 4.191)
			(layers "F.Cu" "F.Mask" "F.Paste")
			(net "PCIE_CONN_TCK")
		)
		(pad "A6" smd rect
			(at 4.99999 0)
			(size 0.7112 4.191)
			(layers "F.Cu" "F.Mask" "F.Paste")
			(net "PCIE_CONN_TDI")
		)
		(pad "A7" smd rect
			(at 5.999988 0)
			(size 0.7112 4.191)
			(layers "F.Cu" "F.Mask" "F.Paste")
			(net "PCIE_CONN_TDO")
		)
		(pad "A8" smd rect
			(at 6.999986 0)
			(size 0.7112 4.191)
			(layers "F.Cu" "F.Mask" "F.Paste")
			(net "PCIE_CONN_TMS")
		)
		(pad "A9" smd rect
			(at 7.999984 0)
			(size 0.7112 4.191)
			(layers "F.Cu" "F.Mask" "F.Paste")
			(net "XP3R3V_PCIE")
		)
		(pad "A10" smd rect
			(at 8.999982 0)
			(size 0.7112 4.191)
			(layers "F.Cu" "F.Mask" "F.Paste")
			(net "XP3R3V_PCIE")
		)
		(pad "A11" smd rect
			(at 9.99998 0)
			(size 0.7112 4.191)
			(layers "F.Cu" "F.Mask" "F.Paste")
			(net "PCIE_CONN_PERST_N")
		)
		(pad "A12" smd rect
			(at 12.999974 0)
			(size 0.7112 4.191)
			(layers "F.Cu" "F.Mask" "F.Paste")
			(net "SG")
		)
		(pad "A13" smd rect
			(at 13.999972 0)
			(size 0.7112 4.191)
			(layers "F.Cu" "F.Mask" "F.Paste")
			(net "C_PCIEREFCLKP")
		)
		(pad "A14" smd rect
			(at 14.99997 0)
			(size 0.7112 4.191)
			(layers "F.Cu" "F.Mask" "F.Paste")
			(net "C_PCIEREFCLKN")
		)
		(pad "A15" smd rect
			(at 15.999968 0)
			(size 0.7112 4.191)
			(layers "F.Cu" "F.Mask" "F.Paste")
			(net "SG")
		)
		(pad "A16" smd rect
			(at 16.999966 0)
			(size 0.7112 4.191)
			(layers "F.Cu" "F.Mask" "F.Paste")
			(net "C_CPU_RX_PCIE_MGT0_TXP")
		)
		(pad "A17" smd rect
			(at 17.999964 0)
			(size 0.7112 4.191)
			(layers "F.Cu" "F.Mask" "F.Paste")
			(net "C_CPU_RX_PCIE_MGT0_TXN")
		)
		(pad "A18" smd rect
			(at 18.999962 0)
			(size 0.7112 4.191)
			(layers "F.Cu" "F.Mask" "F.Paste")
			(net "SG")
		)
		(pad "A19" smd rect
			(at 19.99996 0)
			(size 0.7112 4.191)
			(layers "F.Cu" "F.Mask" "F.Paste")
			(net "Net_752")
		)
		(pad "A20" smd rect
			(at 20.999958 0)
			(size 0.7112 4.191)
			(layers "F.Cu" "F.Mask" "F.Paste")
			(net "SG")
		)
		(pad "A21" smd rect
			(at 21.999956 0)
			(size 0.7112 4.191)
			(layers "F.Cu" "F.Mask" "F.Paste")
			(net "C_CPU_RX_PCIE_MGT1_TXP")
		)
		(pad "A22" smd rect
			(at 22.999954 0)
			(size 0.7112 4.191)
			(layers "F.Cu" "F.Mask" "F.Paste")
			(net "C_CPU_RX_PCIE_MGT1_TXN")
		)
		(pad "A23" smd rect
			(at 23.999952 0)
			(size 0.7112 4.191)
			(layers "F.Cu" "F.Mask" "F.Paste")
			(net "SG")
		)
		(pad "A24" smd rect
			(at 24.99995 0)
			(size 0.7112 4.191)
			(layers "F.Cu" "F.Mask" "F.Paste")
			(net "SG")
		)
		(pad "A25" smd rect
			(at 25.999948 0)
			(size 0.7112 4.191)
			(layers "F.Cu" "F.Mask" "F.Paste")
			(net "C_CPU_RX_PCIE_MGT2_TXP")
		)
		(pad "A26" smd rect
			(at 26.999946 0)
			(size 0.7112 4.191)
			(layers "F.Cu" "F.Mask" "F.Paste")
			(net "C_CPU_RX_PCIE_MGT2_TXN")
		)
		(pad "A27" smd rect
			(at 27.999944 0)
			(size 0.7112 4.191)
			(layers "F.Cu" "F.Mask" "F.Paste")
			(net "SG")
		)
		(pad "A28" smd rect
			(at 28.999942 0)
			(size 0.7112 4.191)
			(layers "F.Cu" "F.Mask" "F.Paste")
			(net "SG")
		)
		(pad "A29" smd rect
			(at 29.99994 0)
			(size 0.7112 4.191)
			(layers "F.Cu" "F.Mask" "F.Paste")
			(net "C_CPU_RX_PCIE_MGT3_TXP")
		)
		(pad "A30" smd rect
			(at 30.999938 0)
			(size 0.7112 4.191)
			(layers "F.Cu" "F.Mask" "F.Paste")
			(net "C_CPU_RX_PCIE_MGT3_TXN")
		)
		(pad "A31" smd rect
			(at 31.999936 0)
			(size 0.7112 4.191)
			(layers "F.Cu" "F.Mask" "F.Paste")
			(net "SG")
		)
		(pad "A32" smd rect
			(at 32.999934 0)
			(size 0.7112 4.191)
			(layers "F.Cu" "F.Mask" "F.Paste")
			(net "Net_750")
		)
		(pad "B1" smd rect
			(at 0 0)
			(size 0.7112 4.191)
			(layers "F.Cu" "F.Mask" "F.Paste")
			(net "XP12R0V_PCIE")
		)
		(pad "B2" smd rect
			(at 0.999998 0)
			(size 0.7112 4.191)
			(layers "F.Cu" "F.Mask" "F.Paste")
			(net "XP12R0V_PCIE")
		)
		(pad "B3" smd rect
			(at 1.999996 0)
			(size 0.7112 4.191)
			(layers "F.Cu" "F.Mask" "F.Paste")
			(net "XP12R0V_PCIE")
		)
		(pad "B4" smd rect
			(at 2.999994 0)
			(size 0.7112 4.191)
			(layers "F.Cu" "F.Mask" "F.Paste")
			(net "SG")
		)
		(pad "B5" smd rect
			(at 3.999992 0)
			(size 0.7112 4.191)
			(layers "F.Cu" "F.Mask" "F.Paste")
			(net "PCIE_CONN_SMCLK")
		)
		(pad "B6" smd rect
			(at 4.99999 0)
			(size 0.7112 4.191)
			(layers "F.Cu" "F.Mask" "F.Paste")
			(net "PCIE_CONN_SMDAT")
		)
		(pad "B7" smd rect
			(at 5.999988 0)
			(size 0.7112 4.191)
			(layers "F.Cu" "F.Mask" "F.Paste")
			(net "SG")
		)
		(pad "B8" smd rect
			(at 6.999986 0)
			(size 0.7112 4.191)
			(layers "F.Cu" "F.Mask" "F.Paste")
			(net "XP3R3V_PCIE")
		)
		(pad "B9" smd rect
			(at 7.999984 0)
			(size 0.7112 4.191)
			(layers "F.Cu" "F.Mask" "F.Paste")
			(net "Net_754")
		)
		(pad "B10" smd rect
			(at 8.999982 0)
			(size 0.7112 4.191)
			(layers "F.Cu" "F.Mask" "F.Paste")
			(net "XP3R3V_AUX_PCIE")
		)
		(pad "B11" smd rect
			(at 9.99998 0)
			(size 0.7112 4.191)
			(layers "F.Cu" "F.Mask" "F.Paste")
			(net "Net_749")
		)
		(pad "B12" smd rect
			(at 12.999974 0)
			(size 0.7112 4.191)
			(layers "F.Cu" "F.Mask" "F.Paste")
			(net "Net_753")
		)
		(pad "B13" smd rect
			(at 13.999972 0)
			(size 0.7112 4.191)
			(layers "F.Cu" "F.Mask" "F.Paste")
			(net "SG")
		)
		(pad "B14" smd rect
			(at 14.99997 0)
			(size 0.7112 4.191)
			(layers "F.Cu" "F.Mask" "F.Paste")
			(net "CPU_TX_PCIE_MGT_0_RXP")
		)
		(pad "B15" smd rect
			(at 15.999968 0)
			(size 0.7112 4.191)
			(layers "F.Cu" "F.Mask" "F.Paste")
			(net "CPU_TX_PCIE_MGT_0_RXN")
		)
		(pad "B16" smd rect
			(at 16.999966 0)
			(size 0.7112 4.191)
			(layers "F.Cu" "F.Mask" "F.Paste")
			(net "SG")
		)
		(pad "B17" smd rect
			(at 17.999964 0)
			(size 0.7112 4.191)
			(layers "F.Cu" "F.Mask" "F.Paste")
			(net "UNNAMED_3_CONN64PGF_I61_PRSNT21")
		)
		(pad "B18" smd rect
			(at 18.999962 0)
			(size 0.7112 4.191)
			(layers "F.Cu" "F.Mask" "F.Paste")
			(net "SG")
		)
		(pad "B19" smd rect
			(at 19.99996 0)
			(size 0.7112 4.191)
			(layers "F.Cu" "F.Mask" "F.Paste")
			(net "CPU_TX_PCIE_MGT_1_RXP")
		)
		(pad "B20" smd rect
			(at 20.999958 0)
			(size 0.7112 4.191)
			(layers "F.Cu" "F.Mask" "F.Paste")
			(net "CPU_TX_PCIE_MGT_1_RXN")
		)
		(pad "B21" smd rect
			(at 21.999956 0)
			(size 0.7112 4.191)
			(layers "F.Cu" "F.Mask" "F.Paste")
			(net "SG")
		)
		(pad "B22" smd rect
			(at 22.999954 0)
			(size 0.7112 4.191)
			(layers "F.Cu" "F.Mask" "F.Paste")
			(net "SG")
		)
		(pad "B23" smd rect
			(at 23.999952 0)
			(size 0.7112 4.191)
			(layers "F.Cu" "F.Mask" "F.Paste")
			(net "CPU_TX_PCIE_MGT_2_RXP")
		)
		(pad "B24" smd rect
			(at 24.99995 0)
			(size 0.7112 4.191)
			(layers "F.Cu" "F.Mask" "F.Paste")
			(net "CPU_TX_PCIE_MGT_2_RXN")
		)
		(pad "B25" smd rect
			(at 25.999948 0)
			(size 0.7112 4.191)
			(layers "F.Cu" "F.Mask" "F.Paste")
			(net "SG")
		)
		(pad "B26" smd rect
			(at 26.999946 0)
			(size 0.7112 4.191)
			(layers "F.Cu" "F.Mask" "F.Paste")
			(net "SG")
		)
		(pad "B27" smd rect
			(at 27.999944 0)
			(size 0.7112 4.191)
			(layers "F.Cu" "F.Mask" "F.Paste")
			(net "CPU_TX_PCIE_MGT_3_RXP")
		)
		(pad "B28" smd rect
			(at 28.999942 0)
			(size 0.7112 4.191)
			(layers "F.Cu" "F.Mask" "F.Paste")
			(net "CPU_TX_PCIE_MGT_3_RXN")
		)
		(pad "B29" smd rect
			(at 29.99994 0)
			(size 0.7112 4.191)
			(layers "F.Cu" "F.Mask" "F.Paste")
			(net "SG")
		)
		(pad "B30" smd rect
			(at 30.999938 0)
			(size 0.7112 4.191)
			(layers "F.Cu" "F.Mask" "F.Paste")
			(net "Net_751")
		)
		(pad "B31" smd rect
			(at 31.999936 -0.4953)
			(size 0.7112 3.2004)
			(layers "F.Cu" "F.Mask" "F.Paste")
			(net "UNNAMED_3_CONN64PGF_I61_PRSNT22")
		)
		(pad "B32" smd rect
			(at 32.999934 0)
			(size 0.7112 4.191)
			(layers "F.Cu" "F.Mask" "F.Paste")
			(net "SG")
		)
		(zone
			(layers "F.Cu" "B.Cu" "In1.Cu" "In2.Cu" "In3.Cu" "In4.Cu" "In5.Cu" "In6.Cu"
				"In7.Cu" "In8.Cu"
			)
			(hatch none 0.5)
			(connect_pads
				(clearance 0)
			)
			(min_thickness 0.25)
			(keepout
				(tracks allowed)
				(vias not_allowed)
				(pads allowed)
				(copperpour not_allowed)
				(footprints allowed)
			)
			(placement
				(enabled no)
				(sheetname "")
			)
			(fill
				(thermal_gap 0.5)
				(thermal_bridge_width 0.5)
				(island_removal_mode 0)
			)
			(polygon
				(pts
					(xy 45.5168 0.004826) (xy 78.7908 0.004826) (xy 79.2988 -0.503174) (xy 79.2988 -6.865874) (xy 45.0088 -6.865874)
					(xy 45.0088 -0.503174)
				)
			)
		)
	)
)
